# S9S_MB_2U (Grand Teton) — schematic netlist excerpt (pin names and nets, part order shuffled) for the footprints in the layout excerpt that follows; sources: Cadence DE-HDL packaged netlist, KiCad conversion of 03242023_DA0F0TMBIJ0_F0T_Motherboard_J_brd_V01_OCP.brd

R688  Q_RES  33.2 1% CHIP  pkg 0402LF  page 229 : A = I3C_SPD_DDRABCD_CPU0_SDA ; B = I3C_SPD_DDRABCD_CPU0_R_SDA
C2356  Q_CAP  10UF 16V 10% X6S  pkg C0805  page 167 : A = P3V3_AUX ; B = GND
R4595  Q_RES  0 5% CHIP  pkg 0402LF  page 296 : A = SMB_VR_3V3AUX_SCL_R ; B = SMB_CLK_PVCCD_HV_CPU1

(kicad_pcb
	(version 20260206)
	(generator "pcbnew")
	(generator_version "10.0")
	(general
		(thickness 1.6)
		(legacy_teardrops no)
	)
	(paper "A4")
	(title_block
		(title "03242023_DA0F0TMBIJ0_F0T_Motherboard_J_brd_V01_OCP.brd")
		(comment 1 "Grand Teton / footprints 4977-4979 of 6105")
	)
	(layers
		(0 "F.Cu" signal "TOP")
		(4 "In1.Cu" signal "GND")
		(6 "In2.Cu" signal "IN1")
		(8 "In3.Cu" signal "GND1")
		(10 "In4.Cu" signal "IN2")
		(12 "In5.Cu" signal "GND2")
		(14 "In6.Cu" signal "IN3")
		(16 "In7.Cu" signal "GND3")
		(18 "In8.Cu" signal "VCC")
		(20 "In9.Cu" signal "VCC1")
		(22 "In10.Cu" signal "GND4")
		(24 "In11.Cu" signal "IN4")
		(26 "In12.Cu" signal "GND5")
		(28 "In13.Cu" signal "IN5")
		(30 "In14.Cu" signal "GND6")
		(32 "In15.Cu" signal "IN6")
		(34 "In16.Cu" signal "GND7")
		(2 "B.Cu" signal "BOTTOM")
		(9 "F.Adhes" user "F.Adhesive")
		(11 "B.Adhes" user "B.Adhesive")
		(13 "F.Paste" user "Package Geometry/Pastemask Top")
		(15 "B.Paste" user "Package Geometry/Pastemask Bottom")
		(5 "F.SilkS" user "Ref Des/Silkscreen Top")
		(7 "B.SilkS" user "Ref Des/Silkscreen Bottom")
		(1 "F.Mask" user "Board Geometry/Soldermask Top")
		(3 "B.Mask" user "Board Geometry/Soldermask Bottom")
		(17 "Dwgs.User" user "User.Drawings")
		(19 "Cmts.User" user "User.Comments")
		(21 "Eco1.User" user "User.Eco1")
		(23 "Eco2.User" user "User.Eco2")
		(25 "Edge.Cuts" user "Board Geometry/Outline")
		(27 "Margin" user)
		(31 "F.CrtYd" user "Package Geometry/Place Bound Top")
		(29 "B.CrtYd" user "Package Geometry/Place Bound Bottom")
		(35 "F.Fab" user "Ref Des/Assembly Top")
		(33 "B.Fab" user "Ref Des/Assembly Bottom")
	)
	(footprint ""
		(layer "B.Cu")
		(at 34.014156 -395.918436 -90)
		(property "Reference" "C2356"
			(at 0 0 90)
			(layer "B.SilkS")
			(hide yes)
			(effects
				(font
					(size 1.27 1.27)
				)
				(justify mirror)
			)
		)
		(property "Value" ""
			(at 0 0 90)
			(layer "B.Fab")
			(effects
				(font
					(size 1.27 1.27)
				)
				(justify mirror)
			)
		)
		(duplicate_pad_numbers_are_jumpers no)
		(fp_line
			(start -1.524 0.762)
			(end 1.524 0.762)
			(stroke
				(width 0.1524)
				(type default)
			)
			(layer "B.SilkS")
		)
		(fp_line
			(start 1.524 0.762)
			(end 1.524 -0.762)
			(stroke
				(width 0.1524)
				(type default)
			)
			(layer "B.SilkS")
		)
		(fp_line
			(start -1.524 -0.762)
			(end -1.524 0.762)
			(stroke
				(width 0.1524)
				(type default)
			)
			(layer "B.SilkS")
		)
		(fp_line
			(start 1.524 -0.762)
			(end -1.524 -0.762)
			(stroke
				(width 0.1524)
				(type default)
			)
			(layer "B.SilkS")
		)
		(fp_line
			(start -1.1049 0.724916)
			(end -1.1049 -0.724916)
			(stroke
				(width 0.1)
				(type default)
			)
			(layer "B.Fab")
		)
		(fp_line
			(start 1.1049 0.724916)
			(end -1.1049 0.724916)
			(stroke
				(width 0.1)
				(type default)
			)
			(layer "B.Fab")
		)
		(fp_line
			(start -1.1049 -0.724916)
			(end 1.1049 -0.724916)
			(stroke
				(width 0.1)
				(type default)
			)
			(layer "B.Fab")
		)
		(fp_line
			(start 1.1049 -0.724916)
			(end 1.1049 0.724916)
			(stroke
				(width 0.1)
				(type default)
			)
			(layer "B.Fab")
		)
		(pad "1" smd rect
			(at 0.889 0 270)
			(size 1.016 1.27)
			(layers "B.Cu" "B.Mask" "B.Paste")
			(net "P3V3_AUX")
		)
		(pad "2" smd rect
			(at -0.889 0 270)
			(size 1.016 1.27)
			(layers "B.Cu" "B.Mask" "B.Paste")
			(net "GND")
		)
	)
	(footprint ""
		(layer "B.Cu")
		(at 22.989032 -171.165774 180)
		(property "Reference" "R4595"
			(at 0 0 0)
			(layer "B.SilkS")
			(hide yes)
			(effects
				(font
					(size 1.27 1.27)
				)
				(justify mirror)
			)
		)
		(property "Value" ""
			(at 0 0 0)
			(layer "B.Fab")
			(effects
				(font
					(size 1.27 1.27)
				)
				(justify mirror)
			)
		)
		(duplicate_pad_numbers_are_jumpers no)
		(fp_line
			(start 0.7874 0.4064)
			(end 0.7874 -0.4064)
			(stroke
				(width 0.1524)
				(type default)
			)
			(layer "B.SilkS")
		)
		(fp_line
			(start 0.7874 -0.4064)
			(end -0.7874 -0.4064)
			(stroke
				(width 0.1524)
				(type default)
			)
			(layer "B.SilkS")
		)
		(fp_line
			(start -0.7874 0.4064)
			(end 0.7874 0.4064)
			(stroke
				(width 0.1524)
				(type default)
			)
			(layer "B.SilkS")
		)
		(fp_line
			(start -0.7874 -0.4064)
			(end -0.7874 0.4064)
			(stroke
				(width 0.1524)
				(type default)
			)
			(layer "B.SilkS")
		)
		(fp_line
			(start 0.67945 0.3048)
			(end 0.67945 -0.305054)
			(stroke
				(width 0.1)
				(type default)
			)
			(layer "B.Fab")
		)
		(fp_line
			(start 0.67945 -0.305054)
			(end 0.12065 -0.305054)
			(stroke
				(width 0.1)
				(type default)
			)
			(layer "B.Fab")
		)
		(fp_line
			(start 0.12065 0.3048)
			(end 0.67945 0.3048)
			(stroke
				(width 0.1)
				(type default)
			)
			(layer "B.Fab")
		)
		(fp_line
			(start 0.12065 0.2794)
			(end 0.12065 0.3048)
			(stroke
				(width 0.1)
				(type default)
			)
			(layer "B.Fab")
		)
		(fp_line
			(start 0.12065 -0.2794)
			(end -0.12065 -0.2794)
			(stroke
				(width 0.1)
				(type default)
			)
			(layer "B.Fab")
		)
		(fp_line
			(start 0.12065 -0.305054)
			(end 0.12065 -0.2794)
			(stroke
				(width 0.1)
				(type default)
			)
			(layer "B.Fab")
		)
		(fp_line
			(start -0.120396 0.3048)
			(end -0.120396 0.2794)
			(stroke
				(width 0.1)
				(type default)
			)
			(layer "B.Fab")
		)
		(fp_line
			(start -0.120396 0.2794)
			(end 0.12065 0.2794)
			(stroke
				(width 0.1)
				(type default)
			)
			(layer "B.Fab")
		)
		(fp_line
			(start -0.12065 -0.2794)
			(end -0.12065 -0.3048)
			(stroke
				(width 0.1)
				(type default)
			)
			(layer "B.Fab")
		)
		(fp_line
			(start -0.12065 -0.3048)
			(end -0.67945 -0.3048)
			(stroke
				(width 0.1)
				(type default)
			)
			(layer "B.Fab")
		)
		(fp_line
			(start -0.67945 0.3048)
			(end -0.120396 0.3048)
			(stroke
				(width 0.1)
				(type default)
			)
			(layer "B.Fab")
		)
		(fp_line
			(start -0.67945 -0.3048)
			(end -0.67945 0.3048)
			(stroke
				(width 0.1)
				(type default)
			)
			(layer "B.Fab")
		)
		(pad "1" smd circle
			(at 0.40005 0)
			(size 0 0)
			(layers "B.Cu" "B.Mask" "B.Paste")
			(net "SMB_VR_3V3AUX_SCL_R")
		)
		(pad "2" smd circle
			(at -0.40005 0)
			(size 0 0)
			(layers "B.Cu" "B.Mask" "B.Paste")
			(net "SMB_CLK_PVCCD_HV_CPU1")
		)
	)
	(footprint ""
		(layer "B.Cu")
		(at 338.998814 -190.756286 90)
		(property "Reference" "R688"
			(at 0 0 90)
			(layer "B.SilkS")
			(hide yes)
			(effects
				(font
					(size 1.27 1.27)
				)
				(justify mirror)
			)
		)
		(property "Value" ""
			(at 0 0 90)
			(layer "B.Fab")
			(effects
				(font
					(size 1.27 1.27)
				)
				(justify mirror)
			)
		)
		(duplicate_pad_numbers_are_jumpers no)
		(fp_line
			(start 0.7874 -0.4064)
			(end -0.7874 -0.4064)
			(stroke
				(width 0.1524)
				(type default)
			)
			(layer "B.SilkS")
		)
		(fp_line
			(start -0.7874 -0.4064)
			(end -0.7874 0.4064)
			(stroke
				(width 0.1524)
				(type default)
			)
			(layer "B.SilkS")
		)
		(fp_line
			(start 0.7874 0.4064)
			(end 0.7874 -0.4064)
			(stroke
				(width 0.1524)
				(type default)
			)
			(layer "B.SilkS")
		)
		(fp_line
			(start -0.7874 0.4064)
			(end 0.7874 0.4064)
			(stroke
				(width 0.1524)
				(type default)
			)
			(layer "B.SilkS")
		)
		(fp_line
			(start 0.67945 -0.305054)
			(end 0.12065 -0.305054)
			(stroke
				(width 0.1)
				(type default)
			)
			(layer "B.Fab")
		)
		(fp_line
			(start 0.12065 -0.305054)
			(end 0.12065 -0.2794)
			(stroke
				(width 0.1)
				(type default)
			)
			(layer "B.Fab")
		)
		(fp_line
			(start -0.12065 -0.3048)
			(end -0.67945 -0.3048)
			(stroke
				(width 0.1)
				(type default)
			)
			(layer "B.Fab")
		)
		(fp_line
			(start -0.67945 -0.3048)
			(end -0.67945 0.3048)
			(stroke
				(width 0.1)
				(type default)
			)
			(layer "B.Fab")
		)
		(fp_line
			(start 0.12065 -0.2794)
			(end -0.12065 -0.2794)
			(stroke
				(width 0.1)
				(type default)
			)
			(layer "B.Fab")
		)
		(fp_line
			(start -0.12065 -0.2794)
			(end -0.12065 -0.3048)
			(stroke
				(width 0.1)
				(type default)
			)
			(layer "B.Fab")
		)
		(fp_line
			(start 0.12065 0.2794)
			(end 0.12065 0.3048)
			(stroke
				(width 0.1)
				(type default)
			)
			(layer "B.Fab")
		)
		(fp_line
			(start -0.120396 0.2794)
			(end 0.12065 0.2794)
			(stroke
				(width 0.1)
				(type default)
			)
			(layer "B.Fab")
		)
		(fp_line
			(start 0.67945 0.3048)
			(end 0.67945 -0.305054)
			(stroke
				(width 0.1)
				(type default)
			)
			(layer "B.Fab")
		)
		(fp_line
			(start 0.12065 0.3048)
			(end 0.67945 0.3048)
			(stroke
				(width 0.1)
				(type default)
			)
			(layer "B.Fab")
		)
		(fp_line
			(start -0.120396 0.3048)
			(end -0.120396 0.2794)
			(stroke
				(width 0.1)
				(type default)
			)
			(layer "B.Fab")
		)
		(fp_line
			(start -0.67945 0.3048)
			(end -0.120396 0.3048)
			(stroke
				(width 0.1)
				(type default)
			)
			(layer "B.Fab")
		)
		(pad "1" smd circle
			(at 0.40005 0 270)
			(size 0 0)
			(layers "B.Cu" "B.Mask" "B.Paste")
			(net "I3C_SPD_DDRABCD_CPU0_SDA")
		)
		(pad "2" smd circle
			(at -0.40005 0 270)
			(size 0 0)
			(layers "B.Cu" "B.Mask" "B.Paste")
			(net "I3C_SPD_DDRABCD_CPU0_R_SDA")
		)
	)
)
